(kicad_pcb
	(version 20260206)
	(generator "pcbnew")
	(generator_version "10.0")
	(general
		(thickness 1.6)
		(legacy_teardrops no)
	)
	(paper "A4")
	(title_block
		(title "Bryce Canyon_R.DPB_16317-1_OCP.brd")
		(comment 1 "Bryce Canyon / footprint 274 of 2099 (SAS1), pads 145-213 of 342")
	)
	(layers
		(0 "F.Cu" signal "TOP")
		(4 "In1.Cu" signal "L2GND")
		(6 "In2.Cu" signal "L3")
		(8 "In3.Cu" signal "L4VCC")
		(10 "In4.Cu" signal "L5VCC")
		(12 "In5.Cu" signal "L6")
		(14 "In6.Cu" signal "L7GND")
		(2 "B.Cu" signal "BOTTOM")
		(9 "F.Adhes" user "F.Adhesive")
		(11 "B.Adhes" user "B.Adhesive")
		(13 "F.Paste" user "Package Geometry/Pastemask Top")
		(15 "B.Paste" user "Package Geometry/Pastemask Bottom")
		(5 "F.SilkS" user "Ref Des/Silkscreen Top")
		(7 "B.SilkS" user "Ref Des/Silkscreen Bottom")
		(1 "F.Mask" user "Board Geometry/Soldermask Top")
		(3 "B.Mask" user "Board Geometry/Soldermask Bottom")
		(17 "Dwgs.User" user "User.Drawings")
		(19 "Cmts.User" user "User.Comments")
		(21 "Eco1.User" user "User.Eco1")
		(23 "Eco2.User" user "User.Eco2")
		(25 "Edge.Cuts" user "Board Geometry/Outline")
		(27 "Margin" user)
		(31 "F.CrtYd" user "Package Geometry/Place Bound Top")
		(29 "B.CrtYd" user "Package Geometry/Place Bound Bottom")
		(35 "F.Fab" user "Ref Des/Assembly Top")
		(33 "B.Fab" user "Ref Des/Assembly Bottom")
	)
	(footprint ""
		(layer "F.Cu")
		(at 287.83661 -238.694468 -90)
		(property "Reference" "SAS1"
			(at 0 0 270)
			(layer "F.SilkS")
			(hide yes)
			(effects
				(font
					(size 1.27 1.27)
				)
			)
		)
		(property "Value" "AMP-CONN342-10R-2-GP"
			(at 20.955 -16.7386 270)
			(unlocked yes)
			(layer "F.Fab")
			(hide yes)
			(effects
				(font
					(size 1.016 1.016)
					(thickness 0.1524)
				)
			)
		)
		(property "Device Type" "PREFIT-342P-668151H483"
			(at 20.955 -18.2626 270)
			(unlocked yes)
			(layer "F.Fab")
			(hide yes)
			(effects
				(font
					(size 1.016 1.016)
					(thickness 0.1524)
				)
			)
		)
		(duplicate_pad_numbers_are_jumpers no)
		(pad "E1" thru_hole circle
			(at 0 7.199884 270)
			(size 0.762 0.762)
			(drill 0.359918)
			(layers "*.Cu" "*.Mask")
			(remove_unused_layers no)
			(net "PHY_SCC_B_TO_DRV_B_5_DP")
			(clearance 0.1651)
			(thermal_gap 0.1651)
		)
		(pad "E2" thru_hole circle
			(at 1.800098 8.199882 270)
			(size 0.762 0.762)
			(drill 0.359918)
			(layers "*.Cu" "*.Mask")
			(remove_unused_layers no)
			(net "PHY_SCC_B_TO_DRV_B_4_DP")
			(clearance 0.1651)
			(thermal_gap 0.1651)
		)
		(pad "E3" thru_hole circle
			(at 3.599942 7.199884 270)
			(size 0.762 0.762)
			(drill 0.359918)
			(layers "*.Cu" "*.Mask")
			(remove_unused_layers no)
			(net "PHY_SCC_B_TO_DRV_B_3_DP")
			(clearance 0.1651)
			(thermal_gap 0.1651)
		)
		(pad "E4" thru_hole circle
			(at 5.40004 8.199882 270)
			(size 0.762 0.762)
			(drill 0.359918)
			(layers "*.Cu" "*.Mask")
			(remove_unused_layers no)
			(net "PHY_SCC_B_TO_DRV_B_2_DP")
			(clearance 0.1651)
			(thermal_gap 0.1651)
		)
		(pad "E5" thru_hole circle
			(at 7.199884 7.199884 270)
			(size 0.762 0.762)
			(drill 0.359918)
			(layers "*.Cu" "*.Mask")
			(remove_unused_layers no)
			(net "PHY_SCC_B_TO_DRV_B_1_DP")
			(clearance 0.1651)
			(thermal_gap 0.1651)
		)
		(pad "E6" thru_hole circle
			(at 8.999982 8.199882 270)
			(size 0.762 0.762)
			(drill 0.359918)
			(layers "*.Cu" "*.Mask")
			(remove_unused_layers no)
			(net "PHY_SCC_B_TO_DRV_B_0_DP")
			(clearance 0.1651)
			(thermal_gap 0.1651)
		)
		(pad "E7" thru_hole circle
			(at 10.80008 7.199884 270)
			(size 0.762 0.762)
			(drill 0.359918)
			(layers "*.Cu" "*.Mask")
			(remove_unused_layers no)
			(net "PHY_SCC_B_TO_DRV_B_6_DP")
			(clearance 0.1651)
			(thermal_gap 0.1651)
		)
		(pad "E8" thru_hole circle
			(at 12.599924 8.199882 270)
			(size 0.762 0.762)
			(drill 0.359918)
			(layers "*.Cu" "*.Mask")
			(remove_unused_layers no)
			(net "PHY_SCC_B_TO_DRV_B_7_DP")
			(clearance 0.1651)
			(thermal_gap 0.1651)
		)
		(pad "E9" thru_hole circle
			(at 14.400022 7.199884 270)
			(size 0.762 0.762)
			(drill 0.359918)
			(layers "*.Cu" "*.Mask")
			(remove_unused_layers no)
			(net "PHY_SCC_B_TO_DRV_B_8_DP")
			(clearance 0.1651)
			(thermal_gap 0.1651)
		)
		(pad "E10" thru_hole circle
			(at 16.20012 8.199882 270)
			(size 0.762 0.762)
			(drill 0.359918)
			(layers "*.Cu" "*.Mask")
			(remove_unused_layers no)
			(net "PHY_SCC_B_TO_DRV_B_9_DP")
			(clearance 0.1651)
			(thermal_gap 0.1651)
		)
		(pad "E11" thru_hole circle
			(at 17.999964 7.199884 270)
			(size 0.762 0.762)
			(drill 0.359918)
			(layers "*.Cu" "*.Mask")
			(remove_unused_layers no)
			(net "PHY_SCC_B_TO_DRV_B_10_DP")
			(clearance 0.1651)
			(thermal_gap 0.1651)
		)
		(pad "E12" thru_hole circle
			(at 19.800062 8.199882 270)
			(size 0.762 0.762)
			(drill 0.359918)
			(layers "*.Cu" "*.Mask")
			(remove_unused_layers no)
			(net "PHY_SCC_B_TO_DRV_B_11_DP")
			(clearance 0.1651)
			(thermal_gap 0.1651)
		)
		(pad "E13" thru_hole circle
			(at 21.599906 7.199884 270)
			(size 0.762 0.762)
			(drill 0.359918)
			(layers "*.Cu" "*.Mask")
			(remove_unused_layers no)
			(net "PHY_SCC_B_TO_DRV_B_12_DP")
			(clearance 0.1651)
			(thermal_gap 0.1651)
		)
		(pad "E14" thru_hole circle
			(at 23.400004 8.199882 270)
			(size 0.762 0.762)
			(drill 0.359918)
			(layers "*.Cu" "*.Mask")
			(remove_unused_layers no)
			(net "PHY_SCC_B_TO_DRV_B_13_DP")
			(clearance 0.1651)
			(thermal_gap 0.1651)
		)
		(pad "E15" thru_hole circle
			(at 25.200102 7.199884 270)
			(size 0.762 0.762)
			(drill 0.359918)
			(layers "*.Cu" "*.Mask")
			(remove_unused_layers no)
			(net "PHY_SCC_B_TO_DRV_B_14_DP")
			(clearance 0.1651)
			(thermal_gap 0.1651)
		)
		(pad "E16" thru_hole circle
			(at 26.999946 8.199882 270)
			(size 0.762 0.762)
			(drill 0.359918)
			(layers "*.Cu" "*.Mask")
			(remove_unused_layers no)
			(net "PHY_SCC_B_TO_DRV_B_15_DP")
			(clearance 0.1651)
			(thermal_gap 0.1651)
		)
		(pad "E17" thru_hole circle
			(at 28.800044 7.199884 270)
			(size 0.762 0.762)
			(drill 0.359918)
			(layers "*.Cu" "*.Mask")
			(remove_unused_layers no)
			(net "PHY_SCC_B_TO_DRV_B_16_DP")
			(clearance 0.1651)
			(thermal_gap 0.1651)
		)
		(pad "E18" thru_hole circle
			(at 30.599888 8.199882 270)
			(size 0.762 0.762)
			(drill 0.359918)
			(layers "*.Cu" "*.Mask")
			(remove_unused_layers no)
			(net "PHY_SCC_B_TO_DRV_B_17_DP")
			(clearance 0.1651)
			(thermal_gap 0.1651)
		)
		(pad "E19" thru_hole circle
			(at 32.399986 7.199884 270)
			(size 0.762 0.762)
			(drill 0.359918)
			(layers "*.Cu" "*.Mask")
			(remove_unused_layers no)
			(net "PHY_SCC_B_TO_DRV_B_23_DP")
			(clearance 0.1651)
			(thermal_gap 0.1651)
		)
		(pad "E20" thru_hole circle
			(at 34.200084 8.199882 270)
			(size 0.762 0.762)
			(drill 0.359918)
			(layers "*.Cu" "*.Mask")
			(remove_unused_layers no)
			(net "PHY_SCC_B_TO_DRV_B_22_DP")
			(clearance 0.1651)
			(thermal_gap 0.1651)
		)
		(pad "E21" thru_hole circle
			(at 35.999928 7.199884 270)
			(size 0.762 0.762)
			(drill 0.359918)
			(layers "*.Cu" "*.Mask")
			(remove_unused_layers no)
			(net "PHY_SCC_B_TO_DRV_B_21_DP")
			(clearance 0.1651)
			(thermal_gap 0.1651)
		)
		(pad "E22" thru_hole circle
			(at 37.800026 8.199882 270)
			(size 0.762 0.762)
			(drill 0.359918)
			(layers "*.Cu" "*.Mask")
			(remove_unused_layers no)
			(net "PHY_SCC_B_TO_DRV_B_20_DP")
			(clearance 0.1651)
			(thermal_gap 0.1651)
		)
		(pad "E23" thru_hole circle
			(at 39.600124 7.199884 270)
			(size 0.762 0.762)
			(drill 0.359918)
			(layers "*.Cu" "*.Mask")
			(remove_unused_layers no)
			(net "PHY_SCC_B_TO_DRV_B_19_DP")
			(clearance 0.1651)
			(thermal_gap 0.1651)
		)
		(pad "E24" thru_hole circle
			(at 41.399968 8.199882 270)
			(size 0.762 0.762)
			(drill 0.359918)
			(layers "*.Cu" "*.Mask")
			(remove_unused_layers no)
			(net "PHY_SCC_B_TO_DRV_B_18_DP")
			(clearance 0.1651)
			(thermal_gap 0.1651)
		)
		(pad "E25" thru_hole circle
			(at 43.200066 7.199884 270)
			(size 0.762 0.762)
			(drill 0.359918)
			(layers "*.Cu" "*.Mask")
			(remove_unused_layers no)
			(net "PHY_SCC_B_TO_DRV_B_24_DP")
			(clearance 0.1651)
			(thermal_gap 0.1651)
		)
		(pad "E26" thru_hole circle
			(at 44.99991 8.199882 270)
			(size 0.762 0.762)
			(drill 0.359918)
			(layers "*.Cu" "*.Mask")
			(remove_unused_layers no)
			(net "PHY_SCC_B_TO_DRV_B_25_DP")
			(clearance 0.1651)
			(thermal_gap 0.1651)
		)
		(pad "E27" thru_hole circle
			(at 46.800008 7.199884 270)
			(size 0.762 0.762)
			(drill 0.359918)
			(layers "*.Cu" "*.Mask")
			(remove_unused_layers no)
			(net "PHY_SCC_B_TO_DRV_B_26_DP")
			(clearance 0.1651)
			(thermal_gap 0.1651)
		)
		(pad "E28" thru_hole circle
			(at 48.600106 8.199882 270)
			(size 0.762 0.762)
			(drill 0.359918)
			(layers "*.Cu" "*.Mask")
			(remove_unused_layers no)
			(net "PHY_SCC_B_TO_DRV_B_27_DP")
			(clearance 0.1651)
			(thermal_gap 0.1651)
		)
		(pad "E29" thru_hole circle
			(at 50.39995 7.199884 270)
			(size 0.762 0.762)
			(drill 0.359918)
			(layers "*.Cu" "*.Mask")
			(remove_unused_layers no)
			(net "PHY_SCC_B_TO_DRV_B_28_DP")
			(clearance 0.1651)
			(thermal_gap 0.1651)
		)
		(pad "E30" thru_hole circle
			(at 52.200048 8.199882 270)
			(size 0.762 0.762)
			(drill 0.359918)
			(layers "*.Cu" "*.Mask")
			(remove_unused_layers no)
			(net "PHY_SCC_B_TO_DRV_B_29_DP")
			(clearance 0.1651)
			(thermal_gap 0.1651)
		)
		(pad "E31" thru_hole circle
			(at 53.999892 7.199884 270)
			(size 0.762 0.762)
			(drill 0.359918)
			(layers "*.Cu" "*.Mask")
			(remove_unused_layers no)
			(net "PHY_SCC_B_TO_DRV_B_35_DP")
			(clearance 0.1651)
			(thermal_gap 0.1651)
		)
		(pad "E32" thru_hole circle
			(at 55.79999 8.199882 270)
			(size 0.762 0.762)
			(drill 0.359918)
			(layers "*.Cu" "*.Mask")
			(remove_unused_layers no)
			(net "PHY_SCC_B_TO_DRV_B_34_DP")
			(clearance 0.1651)
			(thermal_gap 0.1651)
		)
		(pad "E33" thru_hole circle
			(at 57.600088 7.199884 270)
			(size 0.762 0.762)
			(drill 0.359918)
			(layers "*.Cu" "*.Mask")
			(remove_unused_layers no)
			(net "PHY_SCC_B_TO_DRV_B_33_DP")
			(clearance 0.1651)
			(thermal_gap 0.1651)
		)
		(pad "E34" thru_hole circle
			(at 59.399932 8.199882 270)
			(size 0.762 0.762)
			(drill 0.359918)
			(layers "*.Cu" "*.Mask")
			(remove_unused_layers no)
			(net "PHY_SCC_B_TO_DRV_B_32_DP")
			(clearance 0.1651)
			(thermal_gap 0.1651)
		)
		(pad "E35" thru_hole circle
			(at 61.20003 7.199884 270)
			(size 0.762 0.762)
			(drill 0.359918)
			(layers "*.Cu" "*.Mask")
			(remove_unused_layers no)
			(net "PHY_SCC_B_TO_DRV_B_31_DP")
			(clearance 0.1651)
			(thermal_gap 0.1651)
		)
		(pad "E36" thru_hole circle
			(at 62.999874 8.199882 270)
			(size 0.762 0.762)
			(drill 0.359918)
			(layers "*.Cu" "*.Mask")
			(remove_unused_layers no)
			(net "PHY_SCC_B_TO_DRV_B_30_DP")
			(clearance 0.1651)
			(thermal_gap 0.1651)
		)
		(pad "F1" thru_hole circle
			(at 0 8.599932 270)
			(size 0.762 0.762)
			(drill 0.359918)
			(layers "*.Cu" "*.Mask")
			(remove_unused_layers no)
			(net "PHY_SCC_B_TO_DRV_B_5_DN")
			(clearance 0.1651)
			(thermal_gap 0.1651)
		)
		(pad "F2" thru_hole circle
			(at 1.800098 9.59993 270)
			(size 0.762 0.762)
			(drill 0.359918)
			(layers "*.Cu" "*.Mask")
			(remove_unused_layers no)
			(net "PHY_SCC_B_TO_DRV_B_4_DN")
			(clearance 0.1651)
			(thermal_gap 0.1651)
		)
		(pad "F3" thru_hole circle
			(at 3.599942 8.599932 270)
			(size 0.762 0.762)
			(drill 0.359918)
			(layers "*.Cu" "*.Mask")
			(remove_unused_layers no)
			(net "PHY_SCC_B_TO_DRV_B_3_DN")
			(clearance 0.1651)
			(thermal_gap 0.1651)
		)
		(pad "F4" thru_hole circle
			(at 5.40004 9.59993 270)
			(size 0.762 0.762)
			(drill 0.359918)
			(layers "*.Cu" "*.Mask")
			(remove_unused_layers no)
			(net "PHY_SCC_B_TO_DRV_B_2_DN")
			(clearance 0.1651)
			(thermal_gap 0.1651)
		)
		(pad "F5" thru_hole circle
			(at 7.199884 8.599932 270)
			(size 0.762 0.762)
			(drill 0.359918)
			(layers "*.Cu" "*.Mask")
			(remove_unused_layers no)
			(net "PHY_SCC_B_TO_DRV_B_1_DN")
			(clearance 0.1651)
			(thermal_gap 0.1651)
		)
		(pad "F6" thru_hole circle
			(at 8.999982 9.59993 270)
			(size 0.762 0.762)
			(drill 0.359918)
			(layers "*.Cu" "*.Mask")
			(remove_unused_layers no)
			(net "PHY_SCC_B_TO_DRV_B_0_DN")
			(clearance 0.1651)
			(thermal_gap 0.1651)
		)
		(pad "F7" thru_hole circle
			(at 10.80008 8.599932 270)
			(size 0.762 0.762)
			(drill 0.359918)
			(layers "*.Cu" "*.Mask")
			(remove_unused_layers no)
			(net "PHY_SCC_B_TO_DRV_B_6_DN")
			(clearance 0.1651)
			(thermal_gap 0.1651)
		)
		(pad "F8" thru_hole circle
			(at 12.599924 9.59993 270)
			(size 0.762 0.762)
			(drill 0.359918)
			(layers "*.Cu" "*.Mask")
			(remove_unused_layers no)
			(net "PHY_SCC_B_TO_DRV_B_7_DN")
			(clearance 0.1651)
			(thermal_gap 0.1651)
		)
		(pad "F9" thru_hole circle
			(at 14.400022 8.599932 270)
			(size 0.762 0.762)
			(drill 0.359918)
			(layers "*.Cu" "*.Mask")
			(remove_unused_layers no)
			(net "PHY_SCC_B_TO_DRV_B_8_DN")
			(clearance 0.1651)
			(thermal_gap 0.1651)
		)
		(pad "F10" thru_hole circle
			(at 16.20012 9.59993 270)
			(size 0.762 0.762)
			(drill 0.359918)
			(layers "*.Cu" "*.Mask")
			(remove_unused_layers no)
			(net "PHY_SCC_B_TO_DRV_B_9_DN")
			(clearance 0.1651)
			(thermal_gap 0.1651)
		)
		(pad "F11" thru_hole circle
			(at 17.999964 8.599932 270)
			(size 0.762 0.762)
			(drill 0.359918)
			(layers "*.Cu" "*.Mask")
			(remove_unused_layers no)
			(net "PHY_SCC_B_TO_DRV_B_10_DN")
			(clearance 0.1651)
			(thermal_gap 0.1651)
		)
		(pad "F12" thru_hole circle
			(at 19.800062 9.59993 270)
			(size 0.762 0.762)
			(drill 0.359918)
			(layers "*.Cu" "*.Mask")
			(remove_unused_layers no)
			(net "PHY_SCC_B_TO_DRV_B_11_DN")
			(clearance 0.1651)
			(thermal_gap 0.1651)
		)
		(pad "F13" thru_hole circle
			(at 21.599906 8.599932 270)
			(size 0.762 0.762)
			(drill 0.359918)
			(layers "*.Cu" "*.Mask")
			(remove_unused_layers no)
			(net "PHY_SCC_B_TO_DRV_B_12_DN")
			(clearance 0.1651)
			(thermal_gap 0.1651)
		)
		(pad "F14" thru_hole circle
			(at 23.400004 9.59993 270)
			(size 0.762 0.762)
			(drill 0.359918)
			(layers "*.Cu" "*.Mask")
			(remove_unused_layers no)
			(net "PHY_SCC_B_TO_DRV_B_13_DN")
			(clearance 0.1651)
			(thermal_gap 0.1651)
		)
		(pad "F15" thru_hole circle
			(at 25.200102 8.599932 270)
			(size 0.762 0.762)
			(drill 0.359918)
			(layers "*.Cu" "*.Mask")
			(remove_unused_layers no)
			(net "PHY_SCC_B_TO_DRV_B_14_DN")
			(clearance 0.1651)
			(thermal_gap 0.1651)
		)
		(pad "F16" thru_hole circle
			(at 26.999946 9.59993 270)
			(size 0.762 0.762)
			(drill 0.359918)
			(layers "*.Cu" "*.Mask")
			(remove_unused_layers no)
			(net "PHY_SCC_B_TO_DRV_B_15_DN")
			(clearance 0.1651)
			(thermal_gap 0.1651)
		)
		(pad "F17" thru_hole circle
			(at 28.800044 8.599932 270)
			(size 0.762 0.762)
			(drill 0.359918)
			(layers "*.Cu" "*.Mask")
			(remove_unused_layers no)
			(net "PHY_SCC_B_TO_DRV_B_16_DN")
			(clearance 0.1651)
			(thermal_gap 0.1651)
		)
		(pad "F18" thru_hole circle
			(at 30.599888 9.59993 270)
			(size 0.762 0.762)
			(drill 0.359918)
			(layers "*.Cu" "*.Mask")
			(remove_unused_layers no)
			(net "PHY_SCC_B_TO_DRV_B_17_DN")
			(clearance 0.1651)
			(thermal_gap 0.1651)
		)
		(pad "F19" thru_hole circle
			(at 32.399986 8.599932 270)
			(size 0.762 0.762)
			(drill 0.359918)
			(layers "*.Cu" "*.Mask")
			(remove_unused_layers no)
			(net "PHY_SCC_B_TO_DRV_B_23_DN")
			(clearance 0.1651)
			(thermal_gap 0.1651)
		)
		(pad "F20" thru_hole circle
			(at 34.200084 9.59993 270)
			(size 0.762 0.762)
			(drill 0.359918)
			(layers "*.Cu" "*.Mask")
			(remove_unused_layers no)
			(net "PHY_SCC_B_TO_DRV_B_22_DN")
			(clearance 0.1651)
			(thermal_gap 0.1651)
		)
		(pad "F21" thru_hole circle
			(at 35.999928 8.599932 270)
			(size 0.762 0.762)
			(drill 0.359918)
			(layers "*.Cu" "*.Mask")
			(remove_unused_layers no)
			(net "PHY_SCC_B_TO_DRV_B_21_DN")
			(clearance 0.1651)
			(thermal_gap 0.1651)
		)
		(pad "F22" thru_hole circle
			(at 37.800026 9.59993 270)
			(size 0.762 0.762)
			(drill 0.359918)
			(layers "*.Cu" "*.Mask")
			(remove_unused_layers no)
			(net "PHY_SCC_B_TO_DRV_B_20_DN")
			(clearance 0.1651)
			(thermal_gap 0.1651)
		)
		(pad "F23" thru_hole circle
			(at 39.600124 8.599932 270)
			(size 0.762 0.762)
			(drill 0.359918)
			(layers "*.Cu" "*.Mask")
			(remove_unused_layers no)
			(net "PHY_SCC_B_TO_DRV_B_19_DN")
			(clearance 0.1651)
			(thermal_gap 0.1651)
		)
		(pad "F24" thru_hole circle
			(at 41.399968 9.59993 270)
			(size 0.762 0.762)
			(drill 0.359918)
			(layers "*.Cu" "*.Mask")
			(remove_unused_layers no)
			(net "PHY_SCC_B_TO_DRV_B_18_DN")
			(clearance 0.1651)
			(thermal_gap 0.1651)
		)
		(pad "F25" thru_hole circle
			(at 43.200066 8.599932 270)
			(size 0.762 0.762)
			(drill 0.359918)
			(layers "*.Cu" "*.Mask")
			(remove_unused_layers no)
			(net "PHY_SCC_B_TO_DRV_B_24_DN")
			(clearance 0.1651)
			(thermal_gap 0.1651)
		)
		(pad "F26" thru_hole circle
			(at 44.99991 9.59993 270)
			(size 0.762 0.762)
			(drill 0.359918)
			(layers "*.Cu" "*.Mask")
			(remove_unused_layers no)
			(net "PHY_SCC_B_TO_DRV_B_25_DN")
			(clearance 0.1651)
			(thermal_gap 0.1651)
		)
		(pad "F27" thru_hole circle
			(at 46.800008 8.599932 270)
			(size 0.762 0.762)
			(drill 0.359918)
			(layers "*.Cu" "*.Mask")
			(remove_unused_layers no)
			(net "PHY_SCC_B_TO_DRV_B_26_DN")
			(clearance 0.1651)
			(thermal_gap 0.1651)
		)
		(pad "F28" thru_hole circle
			(at 48.600106 9.59993 270)
			(size 0.762 0.762)
			(drill 0.359918)
			(layers "*.Cu" "*.Mask")
			(remove_unused_layers no)
			(net "PHY_SCC_B_TO_DRV_B_27_DN")
			(clearance 0.1651)
			(thermal_gap 0.1651)
		)
		(pad "F29" thru_hole circle
			(at 50.39995 8.599932 270)
			(size 0.762 0.762)
			(drill 0.359918)
			(layers "*.Cu" "*.Mask")
			(remove_unused_layers no)
			(net "PHY_SCC_B_TO_DRV_B_28_DN")
			(clearance 0.1651)
			(thermal_gap 0.1651)
		)
		(pad "F30" thru_hole circle
			(at 52.200048 9.59993 270)
			(size 0.762 0.762)
			(drill 0.359918)
			(layers "*.Cu" "*.Mask")
			(remove_unused_layers no)
			(net "PHY_SCC_B_TO_DRV_B_29_DN")
			(clearance 0.1651)
			(thermal_gap 0.1651)
		)
		(pad "F31" thru_hole circle
			(at 53.999892 8.599932 270)
			(size 0.762 0.762)
			(drill 0.359918)
			(layers "*.Cu" "*.Mask")
			(remove_unused_layers no)
			(net "PHY_SCC_B_TO_DRV_B_35_DN")
			(clearance 0.1651)
			(thermal_gap 0.1651)
		)
		(pad "F32" thru_hole circle
			(at 55.79999 9.59993 270)
			(size 0.762 0.762)
			(drill 0.359918)
			(layers "*.Cu" "*.Mask")
			(remove_unused_layers no)
			(net "PHY_SCC_B_TO_DRV_B_34_DN")
			(clearance 0.1651)
			(thermal_gap 0.1651)
		)
		(pad "F33" thru_hole circle
			(at 57.600088 8.599932 270)
			(size 0.762 0.762)
			(drill 0.359918)
			(layers "*.Cu" "*.Mask")
			(remove_unused_layers no)
			(net "PHY_SCC_B_TO_DRV_B_33_DN")
			(clearance 0.1651)
			(thermal_gap 0.1651)
		)
	)
)
